%FSTAX25Y25*%
%MOIN*%
%SFA1B1*%

%IPPOS*%
%ADD26R,0.039370X0.037400*%
%ADD27R,0.028350X0.039370*%
%ADD28R,0.064960X0.051180*%
%ADD29R,0.017720X0.054330*%
%ADD30R,0.055910X0.061020*%
%ADD31R,0.070870X0.074800*%
%ADD32R,0.039370X0.074800*%
%ADD33R,0.019680X0.090550*%
%ADD34R,0.078740X0.098430*%
%ADD35R,0.086610X0.041340*%
%ADD36R,0.041340X0.039370*%
%ADD37R,0.019680X0.035430*%
%ADD38O,0.057090X0.017720*%
%ADD39R,0.077560X0.022440*%
%ADD40R,0.025590X0.041340*%
%ADD41R,0.051180X0.074800*%
%ADD42R,0.039370X0.090550*%
%ADD43R,0.039370X0.070870*%
%ADD44R,0.053150X0.027560*%
%ADD45R,0.027560X0.045280*%
%ADD46R,0.041340X0.045280*%
%ADD47R,0.050000X0.200000*%
%ADD48R,0.057090X0.037400*%
%ADD49R,0.023620X0.025590*%
%ADD50R,0.135830X0.135830*%
%ADD51O,0.011810X0.027560*%
%ADD52O,0.027560X0.011810*%
%ADD53R,0.028000X0.165000*%
%ADD54R,0.028000X0.126000*%
%ADD55R,0.031500X0.066930*%
%ADD56R,0.070870X0.009840*%
%ADD57R,0.009840X0.022640*%
%ADD58R,0.026570X0.009840*%
%ADD59R,0.038580X0.034250*%
%ADD60R,0.212600X0.114170*%
%ADD61R,0.200790X0.322840*%
%ADD62R,0.096460X0.124020*%
%ADD63R,0.033470X0.039370*%
%ADD64R,0.057090X0.045280*%
%ADD65R,0.037400X0.039370*%
%ADD66R,0.025200X0.026770*%
%ADD67R,0.053150X0.066930*%
%ADD68R,0.009840X0.061020*%
%ADD69R,0.061020X0.009840*%
%ADD70R,0.066930X0.053150*%
%ADD71R,0.045280X0.057090*%
%ADD72R,0.026770X0.025200*%
%ADD73R,0.039370X0.033470*%
%ADD74R,0.039370X0.028350*%
%ADD75R,0.025590X0.023620*%
%ADD76R,0.082870X0.044090*%
%LNgrandmaster-1*%
%LPD*%
G54D26*
X128335Y071D03*
X128965D03*
X121465Y07175D03*
X120835D03*
X091215Y0825D03*
X090585D03*
X077175Y09277D03*
X076545D03*
G54D27*
X1208016Y0856D03*
X1202584D03*
X0952217Y07801D03*
X0946784D03*
X1015784Y0852D03*
X1021216D03*
X1283284Y0682D03*
X1288717D03*
X1271784D03*
X1277217D03*
X1230284Y07455D03*
X1235717D03*
X1010283Y08705D03*
X1015716D03*
X1069716Y0921D03*
X1064283D03*
X1125716D03*
X1120284D03*
X1069716Y09125D03*
X1064283D03*
X1120284Y0913D03*
X1125716D03*
G54D28*
X0818985Y09279D03*
X084556D03*
G54D29*
X0827154Y0917428D03*
X0829713D03*
X0832272D03*
X0834832D03*
X0837391D03*
G54D30*
X0842115Y0917762D03*
X082243D03*
G54D31*
X08368Y09279D03*
G54D32*
X082617Y09279D03*
G54D33*
X0979862Y0902764D03*
X0983012D03*
X0986161D03*
X0989311D03*
X0992461D03*
G54D34*
X0968642Y0924811D03*
Y0903158D03*
X1003681D03*
Y0924811D03*
G54D35*
X06645Y0585193D03*
Y0596807D03*
Y0701807D03*
Y0690193D03*
Y0754307D03*
Y0742693D03*
Y0637693D03*
Y0649307D03*
G54D36*
X0658496Y0591D03*
Y0696D03*
Y07485D03*
Y06435D03*
G54D37*
X0948559Y0875429D03*
X0943441D03*
X0946Y0866571D03*
X0885059Y0875429D03*
X0879941D03*
X08825Y0866571D03*
X0873559Y0875429D03*
X0868441D03*
X0871Y0866571D03*
X0926059Y0875429D03*
X0920941D03*
X09235Y0866571D03*
G54D38*
X0762172Y092035D03*
Y091785D03*
Y091535D03*
Y091285D03*
Y091035D03*
Y090785D03*
Y090535D03*
Y090285D03*
X0783628Y092035D03*
Y091785D03*
Y091535D03*
Y091285D03*
Y091035D03*
Y090785D03*
Y090535D03*
Y090285D03*
X0976272Y088625D03*
Y088375D03*
Y088125D03*
Y087875D03*
Y087625D03*
Y087375D03*
Y087125D03*
Y086875D03*
X0997728Y088625D03*
Y088375D03*
Y088125D03*
Y087875D03*
Y087625D03*
Y087375D03*
Y087125D03*
Y086875D03*
G54D39*
X1214756Y07245D03*
Y07295D03*
Y07345D03*
Y07395D03*
X1234244D03*
Y07345D03*
Y07295D03*
Y07245D03*
X1282244Y07035D03*
Y06985D03*
Y06935D03*
Y06885D03*
X1262756D03*
Y06935D03*
Y06985D03*
Y07035D03*
G54D40*
X1218815Y08705D03*
X1233185D03*
X1187815D03*
X1202185D03*
X1219315Y0857D03*
X1233685D03*
G54D41*
X1271673Y0829799D03*
X1293327D03*
Y0817201D03*
X1271673D03*
G54D42*
X0955949Y0838929D03*
G54D43*
X0938232Y0839913D03*
X0950043Y0821016D03*
X0932327D03*
Y0839913D03*
X0955949Y0821016D03*
X0950043Y0839913D03*
X0944138D03*
X0938232Y0821016D03*
X0944138D03*
G54D44*
X0951535Y0799962D03*
Y0795238D03*
X0943465D03*
Y0799962D03*
G54D45*
X09475Y0805572D03*
Y0789628D03*
G54D46*
X0952126Y0789628D03*
Y0805572D03*
X0942874Y0789628D03*
Y0805572D03*
G54D47*
X08935Y08955D03*
Y0922508D03*
X09035Y08955D03*
Y0922508D03*
X09135Y08955D03*
Y0922508D03*
X09235Y08955D03*
Y0922508D03*
X09335Y08955D03*
Y0922508D03*
G54D48*
X0934Y0874937D03*
Y0867063D03*
X08935Y0874937D03*
Y0867063D03*
X09035Y0874937D03*
Y0867063D03*
X09135Y0874937D03*
Y0867063D03*
G54D49*
X08755Y0797673D03*
Y0794327D03*
X08455Y0556248D03*
Y0559594D03*
X0905Y0556248D03*
Y0559594D03*
X0889Y0797673D03*
Y0794327D03*
X08845Y0797673D03*
Y0794327D03*
X088Y0797673D03*
Y0794327D03*
X08925Y0834827D03*
Y0838173D03*
X08965Y0834827D03*
Y0838173D03*
G54D50*
X08875Y08165D03*
G54D51*
X088061Y0826933D03*
X0882579D03*
X0884547D03*
X0886516D03*
X0888484D03*
X0890453D03*
X0892421D03*
X089439D03*
Y0806067D03*
X0892421D03*
X0890453D03*
X0888484D03*
X0886516D03*
X0884547D03*
X0882579D03*
X088061D03*
G54D52*
X0897933Y082339D03*
Y0821421D03*
Y0819453D03*
Y0817484D03*
Y0815516D03*
Y0813547D03*
Y0811579D03*
Y080961D03*
X0877067D03*
Y0811579D03*
Y0813547D03*
Y0815516D03*
Y0817484D03*
Y0819453D03*
Y0821421D03*
Y082339D03*
G54D53*
X0908661Y0514173D03*
X0786614D03*
X0782677D03*
X077874D03*
X0806299D03*
X0849606D03*
X0892913D03*
X0888976D03*
X0877165D03*
X0873228D03*
X0861417D03*
X085748D03*
X0841732D03*
X0837795D03*
X0814173D03*
X0810236D03*
X0829921D03*
X0900787D03*
X0794488D03*
X0798425D03*
X081811D03*
X089685D03*
X0885039D03*
X0869291D03*
X0865354D03*
X0802362D03*
X0790551D03*
X0881102D03*
X0833858D03*
X0845669D03*
X0853543D03*
G54D54*
X0904724Y0516123D03*
G54D55*
X1108193Y0921D03*
X1094807D03*
X1055693D03*
X1042307D03*
G54D56*
X1005906Y0678356D03*
X0990158D03*
X1005906Y0676356D03*
X0990158D03*
X1005906Y0674356D03*
X0990158D03*
X1005906Y0672356D03*
X0990158D03*
X1005906Y0670356D03*
X0990158D03*
X1005906Y0668356D03*
X0990158D03*
X1005906Y0666356D03*
X0990158D03*
X1005906Y0664356D03*
X0990158D03*
X1005906Y0662356D03*
X0990158D03*
Y0660356D03*
X1005906D03*
G54D57*
X1246953Y0815396D03*
X1245D03*
X1243016D03*
X1241047D03*
Y0833604D03*
X1243016D03*
X1244984D03*
X1246953D03*
G54D58*
X1250152Y0815642D03*
X1237848D03*
Y081761D03*
Y0819579D03*
Y0821547D03*
Y0823516D03*
Y0825484D03*
Y0827453D03*
Y0829421D03*
Y083139D03*
Y0833358D03*
X1250152D03*
Y083139D03*
Y0829421D03*
Y0827453D03*
Y0825484D03*
Y0823516D03*
Y0821547D03*
Y081761D03*
Y0819579D03*
G54D59*
X1014Y0784618D03*
Y0779382D03*
X09205Y0803882D03*
Y0809118D03*
X10425Y0784618D03*
Y0779382D03*
G54D60*
X1267Y0780594D03*
Y0742406D03*
X1231Y0646406D03*
Y0684594D03*
G54D61*
X1085Y082D03*
Y0879745D03*
G54D62*
X0692279Y0591D03*
X071472D03*
Y0696D03*
X0692279D03*
X071472Y07485D03*
X0692279D03*
Y06435D03*
X071472D03*
G54D63*
X0724Y0920146D03*
Y0925854D03*
X0958Y0891354D03*
Y0885646D03*
Y0873146D03*
Y0878854D03*
X06635Y0925854D03*
Y0920146D03*
X0683667Y0925854D03*
Y0920146D03*
X0703833D03*
Y0925854D03*
G54D64*
X1033Y0785543D03*
Y0778457D03*
X12325Y0718543D03*
Y0711457D03*
X1265Y0709957D03*
Y0717043D03*
X1224409Y0775984D03*
Y0783071D03*
X123622Y0775984D03*
Y0783071D03*
X10095Y0884543D03*
Y0877457D03*
X082Y0864957D03*
Y0872043D03*
X0863Y0861043D03*
Y0853957D03*
X09684Y0812157D03*
Y0819243D03*
X09125Y0802457D03*
Y0809543D03*
X08965Y0799543D03*
Y0792457D03*
X10055Y0785543D03*
Y0778457D03*
X0995Y0785543D03*
Y0778457D03*
X10225Y0785543D03*
Y0778457D03*
G54D65*
X1003Y080965D03*
Y080335D03*
X1246Y073065D03*
Y072435D03*
X1251Y070215D03*
Y069585D03*
X10185Y088415D03*
Y087785D03*
X09679Y083335D03*
Y082705D03*
X09045Y080335D03*
Y080965D03*
X12595Y083315D03*
Y082685D03*
Y081335D03*
Y081965D03*
G54D66*
X101Y0808193D03*
Y0804807D03*
X1293Y0692693D03*
Y0689307D03*
X12055Y0738193D03*
Y0734807D03*
X12575Y0807693D03*
Y0804307D03*
X0813Y0866807D03*
Y0870193D03*
X08715Y0859693D03*
Y0856307D03*
X0976Y0820507D03*
Y0823893D03*
X10445Y0808193D03*
Y0804807D03*
X10385Y0808193D03*
Y0804807D03*
X10325Y0808193D03*
Y0804807D03*
X10265Y0808193D03*
Y0804807D03*
X1021Y0808193D03*
Y0804807D03*
X10155Y0808193D03*
Y0804807D03*
G54D67*
X0901514Y0744247D03*
X0901515Y0596253D03*
X0815885D03*
X0815884Y0744247D03*
G54D68*
X0820314Y0604225D03*
Y0588281D03*
X0830157D03*
X0839999D03*
X0849842D03*
X0859684D03*
X086559D03*
X0871495D03*
X0877401D03*
X0883306D03*
X0889212D03*
X0830157Y0604225D03*
X0839999D03*
X0849842D03*
X0859684D03*
X086559D03*
X0871495D03*
X0877401D03*
X0883306D03*
X0889212D03*
X0895117Y0588281D03*
Y0604225D03*
X0897086D03*
Y0588281D03*
X0893149Y0604225D03*
Y0588281D03*
X089118Y0604225D03*
Y0588281D03*
X0887243Y0604225D03*
X0885275D03*
X085181D03*
X0853779D03*
X0832125D03*
X0834094D03*
X0822283D03*
X0824251D03*
X082622D03*
X0828188D03*
X0843936D03*
X0847873D03*
X0845905D03*
X0841968D03*
X0838031D03*
X0836062D03*
X0855747D03*
X082622Y0588281D03*
X0824251D03*
X0845905D03*
X0843936D03*
X0855747D03*
X0853779D03*
X085181D03*
X0847873D03*
X0838031D03*
X0828188D03*
X0832125D03*
X0834094D03*
X0836062D03*
X0841968D03*
X0822283D03*
X0863621Y0604225D03*
X0861653D03*
X0869527Y0588281D03*
X0867558D03*
X0881338D03*
X0879369D03*
X0875432Y0604225D03*
X0873464D03*
X0861653Y0588281D03*
X0863621D03*
X0857716Y0604225D03*
Y0588281D03*
X0869527Y0604225D03*
X0867558D03*
X0875432Y0588281D03*
X0873464D03*
X0887243D03*
X0885275D03*
X0881338Y0604225D03*
X0879369D03*
X0832124Y0752219D03*
X0830156D03*
X0826219Y0736275D03*
X0832124D03*
X0830156D03*
X082425D03*
X0895116Y0752219D03*
X0893148D03*
X0885274D03*
X0883305D03*
X0891179D03*
X0889211D03*
X0875431D03*
X0873463D03*
X0881337D03*
X0879368D03*
X0865589D03*
X086362D03*
X0871494D03*
X0869526D03*
X0855746D03*
X0861652D03*
X0853778D03*
X0859683D03*
X0845904D03*
X0843935D03*
X0851809D03*
X0849841D03*
X0836061D03*
X0834093D03*
X0841967D03*
X0839998D03*
X0826219D03*
X082425D03*
X0820313Y0736275D03*
X0822282D03*
Y0752219D03*
X0820313D03*
X0836061Y0736275D03*
X0834093D03*
X0841967D03*
X0839998D03*
X0845904D03*
X0843935D03*
X0851809D03*
X0849841D03*
X0855746D03*
X0853778D03*
X0861652D03*
X0859683D03*
X0865589D03*
X086362D03*
X0871494D03*
X0869526D03*
X0875431D03*
X0873463D03*
X0881337D03*
X0879368D03*
X0885274D03*
X0883305D03*
X0891179D03*
X0889211D03*
X0895116D03*
X0893148D03*
X0828187D03*
X083803D03*
X0847872D03*
X0857715D03*
X0867557D03*
X08774D03*
X0887242D03*
X0828187Y0752219D03*
X083803D03*
X0847872D03*
X0857715D03*
X0867557D03*
X08774D03*
X0887242D03*
X0897085Y0736275D03*
Y0752219D03*
G54D69*
X0760727Y0707164D03*
X0776671Y0654015D03*
Y0707164D03*
Y0709133D03*
X0760727D03*
Y069929D03*
Y0689448D03*
Y0679605D03*
Y0669763D03*
Y065992D03*
Y0650078D03*
Y0640235D03*
X0776671Y069929D03*
Y0689448D03*
Y0679605D03*
Y0669763D03*
Y065992D03*
Y0650078D03*
Y0640235D03*
Y0705196D03*
X0760727D03*
X0776671Y0652046D03*
X0760727Y0665826D03*
Y0671731D03*
X0776671Y0648109D03*
X0760727Y0632361D03*
X0776671Y0642204D03*
Y0632361D03*
Y0638267D03*
X0760727Y0677637D03*
Y0663857D03*
Y063433D03*
X0776671Y0636298D03*
X0760727Y0675668D03*
Y0642204D03*
Y0648109D03*
Y0638267D03*
Y0667794D03*
Y06737D03*
Y0661889D03*
Y0655983D03*
Y0654015D03*
Y0644172D03*
Y0657952D03*
X0776671Y063433D03*
X0760727Y0636298D03*
X0776671Y0644172D03*
X0760727Y0683542D03*
Y0681574D03*
Y0646141D03*
Y0652046D03*
X0776671Y0657952D03*
Y0655983D03*
X0760727Y0695353D03*
X0776671Y0671731D03*
Y0675668D03*
X0760727Y0701259D03*
X0776671Y0665826D03*
Y0681574D03*
Y0685511D03*
Y0693385D03*
X0760727Y0697322D03*
Y0687479D03*
X0776671Y0667794D03*
Y0646141D03*
Y0697322D03*
Y0701259D03*
X0760727Y0703227D03*
Y0691416D03*
Y0685511D03*
Y0693385D03*
X0776671Y0677637D03*
Y06737D03*
Y0695353D03*
Y0683542D03*
Y0691416D03*
Y0703227D03*
Y0687479D03*
Y0661889D03*
Y0663857D03*
X0964162Y0703223D03*
Y0705192D03*
Y070716D03*
Y0709129D03*
X0948218Y0703223D03*
Y0705192D03*
Y070716D03*
Y0709129D03*
Y0644168D03*
Y0659916D03*
Y0657948D03*
X0964162Y0654011D03*
X0948218Y0675664D03*
Y0673696D03*
X0964162Y0632357D03*
X0948218D03*
X0964162Y0634326D03*
Y0636294D03*
Y0638263D03*
Y0640231D03*
Y0644168D03*
Y0646137D03*
Y0648105D03*
Y0650074D03*
X0948218Y0654011D03*
X0964162Y0659916D03*
X0948218Y0695349D03*
X0964162Y06422D03*
Y0652042D03*
Y0661885D03*
Y0671727D03*
Y068157D03*
Y0691412D03*
Y0701255D03*
X0948218Y06422D03*
Y0652042D03*
Y0661885D03*
Y0671727D03*
Y068157D03*
Y0691412D03*
Y0701255D03*
Y0655979D03*
Y0693381D03*
X0964162Y0663853D03*
Y066779D03*
Y0655979D03*
Y0657948D03*
Y0665822D03*
Y0675664D03*
Y0673696D03*
X0948218Y0669759D03*
Y0665822D03*
Y066779D03*
Y0663853D03*
X0964162Y0669759D03*
X0948218Y0697318D03*
Y0699286D03*
X0964162Y0697318D03*
Y0699286D03*
Y0695349D03*
Y0683538D03*
Y0685507D03*
Y0677633D03*
Y0679601D03*
X0948218Y0636294D03*
Y0634326D03*
X0964162Y0693381D03*
Y0689444D03*
Y0687475D03*
X0948218Y0683538D03*
Y0687475D03*
Y0685507D03*
Y0689444D03*
Y0679601D03*
Y0650074D03*
Y0677633D03*
Y0648105D03*
Y0646137D03*
Y0638263D03*
Y0640231D03*
G54D70*
X0768699Y0713562D03*
Y0627932D03*
X095619Y0627928D03*
Y0713558D03*
G54D71*
X1181043Y0852D03*
X1173957D03*
X1269043Y06425D03*
X1261957D03*
X1269043Y06535D03*
X1261957D03*
X1250043Y08075D03*
X1242957D03*
X0964957Y0573D03*
X0972043D03*
X0917043Y0817D03*
X0909957D03*
X0786343Y0928D03*
X0779257D03*
X1019957Y0825D03*
X1027043D03*
G54D72*
X1166693Y0852D03*
X1163307D03*
X1235193Y0766D03*
X1231807D03*
X1235193Y07505D03*
X1231807D03*
X1235193Y0756D03*
X1231807D03*
X1235193Y07615D03*
X1231807D03*
X1263307Y06615D03*
X1266693D03*
X1263307Y06675D03*
X1266693D03*
X1263307Y06725D03*
X1266693D03*
X1263307Y0678D03*
X1266693D03*
X0967307Y0564D03*
X0970693D03*
G54D73*
X1029146Y0852D03*
X1034854D03*
G54D74*
X1274Y0709283D03*
Y0714716D03*
X12225Y0713283D03*
Y0718716D03*
X13Y0694216D03*
Y0688784D03*
X11995Y0734283D03*
Y0739716D03*
X08137Y0768317D03*
Y0762884D03*
X0662913Y0909717D03*
Y0904284D03*
X0683079D03*
Y0909717D03*
X0703246Y0904284D03*
Y0909717D03*
X0723413Y0904284D03*
Y0909717D03*
X12113Y0743784D03*
Y0749217D03*
X07924Y0913317D03*
Y0907883D03*
G54D75*
X0965827Y08865D03*
X0969173D03*
X0965827Y0879D03*
X0969173D03*
G54D76*
X08495Y0864622D03*
Y0848874D03*
Y0856748D03*
Y0841D03*
X0832Y0864622D03*
Y0856748D03*
Y0848874D03*
Y0841D03*
M02*